# T6G (Grand Teton) — schematic netlist excerpt (pin names and nets, part order shuffled) for the footprints in the layout excerpt that follows; sources: Cadence DE-HDL packaged netlist, KiCad conversion of 04192023_DAF0TMB3IC0_F0TG_MB_C_brd_V02_OCP.brd

U8004  74LVC2G07DW7  74LVC2G07DW-7 EMPTY  pkg SOT363_0-65_2X1-25XC  page 242
  \1a\  = FM_AC_PWR_BTN_PLD_N
  GND  = GND
  \2a\  = GND
  \2y\  = NC_U8004_2Y
  VCC  = P3V3_AUX
  \1y\  = FM_AC_PWR_BTN_PLD_ISO_R_N

R6044  Q_RES  10K 5% CHIP  pkg 0402LF  page 167 : A = FM_FORCE_ALL_PWRON ; B = GND

(kicad_pcb
	(version 20260206)
	(generator "pcbnew")
	(generator_version "10.0")
	(general
		(thickness 1.6)
		(legacy_teardrops no)
	)
	(paper "A4")
	(title_block
		(title "04192023_DAF0TMB3IC0_F0TG_MB_C_brd_V02_OCP.brd")
		(comment 1 "Grand Teton / footprints 7421-7422 of 8354")
	)
	(layers
		(0 "F.Cu" signal "TOP")
		(4 "In1.Cu" signal "GND")
		(6 "In2.Cu" signal "IN1")
		(8 "In3.Cu" signal "GND1")
		(10 "In4.Cu" signal "IN2")
		(12 "In5.Cu" signal "GND2")
		(14 "In6.Cu" signal "IN3")
		(16 "In7.Cu" signal "GND3")
		(18 "In8.Cu" signal "VCC")
		(20 "In9.Cu" signal "VCC1")
		(22 "In10.Cu" signal "GND4")
		(24 "In11.Cu" signal "IN4")
		(26 "In12.Cu" signal "GND5")
		(28 "In13.Cu" signal "IN5")
		(30 "In14.Cu" signal "GND6")
		(32 "In15.Cu" signal "IN6")
		(34 "In16.Cu" signal "GND7")
		(2 "B.Cu" signal "BOTTOM")
		(9 "F.Adhes" user "F.Adhesive")
		(11 "B.Adhes" user "B.Adhesive")
		(13 "F.Paste" user "Package Geometry/Pastemask Top")
		(15 "B.Paste" user "Package Geometry/Pastemask Bottom")
		(5 "F.SilkS" user "Ref Des/Silkscreen Top")
		(7 "B.SilkS" user "Ref Des/Silkscreen Bottom")
		(1 "F.Mask" user "Board Geometry/Soldermask Top")
		(3 "B.Mask" user "Board Geometry/Soldermask Bottom")
		(17 "Dwgs.User" user "User.Drawings")
		(19 "Cmts.User" user "User.Comments")
		(21 "Eco1.User" user "User.Eco1")
		(23 "Eco2.User" user "User.Eco2")
		(25 "Edge.Cuts" user "Board Geometry/Outline")
		(27 "Margin" user)
		(31 "F.CrtYd" user "Package Geometry/Place Bound Top")
		(29 "B.CrtYd" user "Package Geometry/Place Bound Bottom")
		(35 "F.Fab" user "Ref Des/Assembly Top")
		(33 "B.Fab" user "Ref Des/Assembly Bottom")
	)
	(footprint ""
		(layer "B.Cu")
		(at 201.041 -140.462 90)
		(property "Reference" "U8004"
			(at -2.036826 -2.62509 270)
			(unlocked yes)
			(layer "B.SilkS")
			(effects
				(font
					(size 0.7874 0.5842)
					(thickness 0.1524)
				)
				(justify left mirror)
			)
		)
		(property "Value" ""
			(at 0 0 90)
			(layer "B.Fab")
			(effects
				(font
					(size 1.27 1.27)
				)
				(justify mirror)
			)
		)
		(duplicate_pad_numbers_are_jumpers no)
		(fp_line
			(start 1.38176 -1.100074)
			(end 1.38176 1.100074)
			(stroke
				(width 0.1524)
				(type default)
			)
			(layer "B.SilkS")
		)
		(fp_line
			(start 0.592074 -1.100074)
			(end 1.38176 -1.100074)
			(stroke
				(width 0.1524)
				(type default)
			)
			(layer "B.SilkS")
		)
		(fp_line
			(start -0.592074 -1.100074)
			(end 0 -0.508)
			(stroke
				(width 0.1524)
				(type default)
			)
			(layer "B.SilkS")
		)
		(fp_line
			(start -1.38176 -1.100074)
			(end -0.592074 -1.100074)
			(stroke
				(width 0.1524)
				(type default)
			)
			(layer "B.SilkS")
		)
		(fp_line
			(start 0 -0.508)
			(end 0.592074 -1.100074)
			(stroke
				(width 0.1524)
				(type default)
			)
			(layer "B.SilkS")
		)
		(fp_line
			(start 1.38176 1.100074)
			(end -1.38176 1.100074)
			(stroke
				(width 0.1524)
				(type default)
			)
			(layer "B.SilkS")
		)
		(fp_line
			(start -1.38176 1.100074)
			(end -1.38176 -1.100074)
			(stroke
				(width 0.1524)
				(type default)
			)
			(layer "B.SilkS")
		)
		(fp_poly
			(pts
				(xy 1.9431 -0.870204) (xy 1.50241 -0.649986) (xy 1.9431 -0.429768)
			)
			(stroke
				(width 0)
				(type default)
			)
			(fill yes)
			(layer "B.SilkS")
		)
		(fp_line
			(start 0.674878 -1.100074)
			(end 0.674878 1.100074)
			(stroke
				(width 0.1)
				(type default)
			)
			(layer "B.Fab")
		)
		(fp_line
			(start -0.674878 -1.100074)
			(end 0.674878 -1.100074)
			(stroke
				(width 0.1)
				(type default)
			)
			(layer "B.Fab")
		)
		(fp_line
			(start 0.674878 1.100074)
			(end -0.674878 1.100074)
			(stroke
				(width 0.1)
				(type default)
			)
			(layer "B.Fab")
		)
		(fp_line
			(start -0.674878 1.100074)
			(end -0.674878 -1.100074)
			(stroke
				(width 0.1)
				(type default)
			)
			(layer "B.Fab")
		)
		(fp_poly
			(pts
				(xy 1.9431 -0.870204) (xy 1.50241 -0.649986) (xy 1.9431 -0.429768)
			)
			(stroke
				(width 0)
				(type default)
			)
			(fill yes)
			(layer "B.Fab")
		)
		(pad "1" smd rect
			(at 0.94996 -0.649986)
			(size 0.4318 0.6096)
			(layers "B.Cu" "B.Mask" "B.Paste")
			(net "FM_AC_PWR_BTN_PLD_N")
		)
		(pad "2" smd rect
			(at 0.94996 0)
			(size 0.4318 0.6096)
			(layers "B.Cu" "B.Mask" "B.Paste")
			(net "GND")
		)
		(pad "3" smd rect
			(at 0.94996 0.649986)
			(size 0.4318 0.6096)
			(layers "B.Cu" "B.Mask" "B.Paste")
			(net "GND")
		)
		(pad "4" smd rect
			(at -0.94996 0.649986)
			(size 0.4318 0.6096)
			(layers "B.Cu" "B.Mask" "B.Paste")
			(net "NC_U8004_2Y")
		)
		(pad "5" smd rect
			(at -0.94996 0)
			(size 0.4318 0.6096)
			(layers "B.Cu" "B.Mask" "B.Paste")
			(net "P3V3_AUX")
		)
		(pad "6" smd rect
			(at -0.94996 -0.649986)
			(size 0.4318 0.6096)
			(layers "B.Cu" "B.Mask" "B.Paste")
			(net "FM_AC_PWR_BTN_PLD_ISO_R_N")
		)
	)
	(footprint ""
		(layer "B.Cu")
		(at 428.98695 -41.087548)
		(property "Reference" "R6044"
			(at 0 0 0)
			(layer "B.SilkS")
			(hide yes)
			(effects
				(font
					(size 1.27 1.27)
				)
				(justify mirror)
			)
		)
		(property "Value" ""
			(at 0 0 0)
			(layer "B.Fab")
			(effects
				(font
					(size 1.27 1.27)
				)
				(justify mirror)
			)
		)
		(duplicate_pad_numbers_are_jumpers no)
		(fp_line
			(start -0.7874 -0.4064)
			(end -0.7874 0.4064)
			(stroke
				(width 0.1524)
				(type default)
			)
			(layer "B.SilkS")
		)
		(fp_line
			(start -0.7874 0.4064)
			(end 0.7874 0.4064)
			(stroke
				(width 0.1524)
				(type default)
			)
			(layer "B.SilkS")
		)
		(fp_line
			(start 0.7874 -0.4064)
			(end -0.7874 -0.4064)
			(stroke
				(width 0.1524)
				(type default)
			)
			(layer "B.SilkS")
		)
		(fp_line
			(start 0.7874 0.4064)
			(end 0.7874 -0.4064)
			(stroke
				(width 0.1524)
				(type default)
			)
			(layer "B.SilkS")
		)
		(fp_line
			(start -0.67945 -0.3048)
			(end -0.67945 0.3048)
			(stroke
				(width 0.1)
				(type default)
			)
			(layer "B.Fab")
		)
		(fp_line
			(start -0.67945 0.3048)
			(end -0.120396 0.3048)
			(stroke
				(width 0.1)
				(type default)
			)
			(layer "B.Fab")
		)
		(fp_line
			(start -0.12065 -0.3048)
			(end -0.67945 -0.3048)
			(stroke
				(width 0.1)
				(type default)
			)
			(layer "B.Fab")
		)
		(fp_line
			(start -0.12065 -0.2794)
			(end -0.12065 -0.3048)
			(stroke
				(width 0.1)
				(type default)
			)
			(layer "B.Fab")
		)
		(fp_line
			(start -0.120396 0.2794)
			(end 0.12065 0.2794)
			(stroke
				(width 0.1)
				(type default)
			)
			(layer "B.Fab")
		)
		(fp_line
			(start -0.120396 0.3048)
			(end -0.120396 0.2794)
			(stroke
				(width 0.1)
				(type default)
			)
			(layer "B.Fab")
		)
		(fp_line
			(start 0.12065 -0.305054)
			(end 0.12065 -0.2794)
			(stroke
				(width 0.1)
				(type default)
			)
			(layer "B.Fab")
		)
		(fp_line
			(start 0.12065 -0.2794)
			(end -0.12065 -0.2794)
			(stroke
				(width 0.1)
				(type default)
			)
			(layer "B.Fab")
		)
		(fp_line
			(start 0.12065 0.2794)
			(end 0.12065 0.3048)
			(stroke
				(width 0.1)
				(type default)
			)
			(layer "B.Fab")
		)
		(fp_line
			(start 0.12065 0.3048)
			(end 0.67945 0.3048)
			(stroke
				(width 0.1)
				(type default)
			)
			(layer "B.Fab")
		)
		(fp_line
			(start 0.67945 -0.305054)
			(end 0.12065 -0.305054)
			(stroke
				(width 0.1)
				(type default)
			)
			(layer "B.Fab")
		)
		(fp_line
			(start 0.67945 0.3048)
			(end 0.67945 -0.305054)
			(stroke
				(width 0.1)
				(type default)
			)
			(layer "B.Fab")
		)
		(pad "1" smd circle
			(at 0.40005 0 180)
			(size 0 0)
			(layers "B.Cu" "B.Mask" "B.Paste")
			(net "FM_FORCE_ALL_PWRON")
		)
		(pad "2" smd circle
			(at -0.40005 0 180)
			(size 0 0)
			(layers "B.Cu" "B.Mask" "B.Paste")
			(net "GND")
		)
	)
)
